(kicad_pcb
	(version 20240108)
	(generator "pcbnew")
	(generator_version "8.0")
	(general
		(thickness 1.62)
		(legacy_teardrops no)
	)
	(paper "A4")
	(title_block
		(title "Jetson Orin Baseboard")
		(date "2025-03-12")
		(rev "1.3.4")
		(company "Antmicro Ltd")
		(comment 1 "www.antmicro.com")
		(comment 9 "footprints 37-39 of 677")
	)
	(layers
		(0 "F.Cu" signal)
		(1 "In1.Cu" signal)
		(2 "In2.Cu" signal)
		(3 "In3.Cu" signal)
		(4 "In4.Cu" jumper)
		(5 "In5.Cu" signal)
		(6 "In6.Cu" signal)
		(31 "B.Cu" signal)
		(32 "B.Adhes" user "B.Adhesive")
		(33 "F.Adhes" user "F.Adhesive")
		(34 "B.Paste" user)
		(35 "F.Paste" user)
		(36 "B.SilkS" user "B.Silkscreen")
		(37 "F.SilkS" user "F.Silkscreen")
		(38 "B.Mask" user)
		(39 "F.Mask" user)
		(40 "Dwgs.User" user "User.Drawings")
		(41 "Cmts.User" user "User.Comments")
		(42 "Eco1.User" user "User.Eco1")
		(43 "Eco2.User" user "User.Eco2")
		(44 "Edge.Cuts" user)
		(45 "Margin" user)
		(46 "B.CrtYd" user "B.Courtyard")
		(47 "F.CrtYd" user "F.Courtyard")
		(48 "B.Fab" user)
		(49 "F.Fab" user)
	)
	(footprint "antmicro-footprints:XDFN-2_1x0.60mm"
		(layer "F.Cu")
		(at 147.45 85.6 -90)
		(property "Reference" "D46"
			(at -5.89 0.15 180)
			(layer "F.SilkS")
			(effects
				(font
					(size 0.7 0.7)
					(thickness 0.15)
				)
				(justify left bottom)
			)
		)
		(property "Value" "TPD1E0B04_XDFN-2"
			(at 0 1.5 -90)
			(layer "F.Fab")
			(effects
				(font
					(size 0.7 0.7)
					(thickness 0.15)
				)
				(justify left bottom)
			)
		)
		(property "Footprint" "antmicro-footprints:XDFN-2_1x0.60mm"
			(at 0 0 -90)
			(layer "F.Fab")
			(hide yes)
			(effects
				(font
					(size 1.27 1.27)
					(thickness 0.15)
				)
			)
		)
		(property "Datasheet" "https://www.ti.com/general/docs/suppproductinfo.tsp?distId=26&gotoUrl=https://www.ti.com/lit/gpn/tpd1e0b04"
			(at 0 0 -90)
			(layer "F.Fab")
			(hide yes)
			(effects
				(font
					(size 1.27 1.27)
					(thickness 0.15)
				)
			)
		)
		(property "MPN" "TPD1E0B04DPYR"
			(at 61.85 233.05 0)
			(layer "F.Fab")
			(hide yes)
			(effects
				(font
					(size 1 1)
					(thickness 0.15)
				)
			)
		)
		(property "Manufacturer" "Texas Instruments"
			(at 61.85 233.05 0)
			(layer "F.Fab")
			(hide yes)
			(effects
				(font
					(size 1 1)
					(thickness 0.15)
				)
			)
		)
		(property "Author" "Antmicro"
			(at 61.85 233.05 0)
			(layer "F.Fab")
			(hide yes)
			(effects
				(font
					(size 1 1)
					(thickness 0.15)
				)
			)
		)
		(property "License" "Apache-2.0"
			(at 61.85 233.05 0)
			(layer "F.Fab")
			(hide yes)
			(effects
				(font
					(size 1 1)
					(thickness 0.15)
				)
			)
		)
		(sheetname "Peripherals")
		(sheetfile "peripherals.kicad_sch")
		(attr smd)
		(fp_rect
			(start -0.725 -0.475)
			(end 0.725 0.475)
			(stroke
				(width 0.05)
				(type solid)
			)
			(fill none)
			(layer "F.CrtYd")
		)
		(fp_rect
			(start -0.55 -0.35)
			(end 0.55 0.35)
			(stroke
				(width 0.15)
				(type solid)
			)
			(fill none)
			(layer "F.Fab")
		)
		(fp_text user "Author: Antmicro"
			(at -0.8 4.4 -90)
			(layer "F.Fab")
			(hide yes)
			(effects
				(font
					(size 0.7 0.7)
					(thickness 0.15)
				)
				(justify left bottom)
			)
		)
		(fp_text user "License: Apache-2.0"
			(at -0.8 5.6 -90)
			(layer "F.Fab")
			(hide yes)
			(effects
				(font
					(size 0.7 0.7)
					(thickness 0.15)
				)
				(justify left bottom)
			)
		)
		(fp_text user "${REFERENCE}"
			(at -0.8 3.2 -90)
			(layer "F.Fab")
			(hide yes)
			(effects
				(font
					(size 0.7 0.7)
					(thickness 0.15)
				)
				(justify left bottom)
			)
		)
		(pad "1" smd roundrect
			(at -0.351 0 270)
			(size 0.3 0.5)
			(layers "F.Cu" "F.Paste" "F.Mask")
			(roundrect_rratio 0.25)
			(net 175 "PCIE2_RX1_P")
			(pinfunction "C")
			(pintype "passive")
		)
		(pad "2" smd roundrect
			(at 0.349 0 270)
			(size 0.3 0.5)
			(layers "F.Cu" "F.Paste" "F.Mask")
			(roundrect_rratio 0.25)
			(net 1 "GND")
			(pinfunction "A")
			(pintype "passive")
		)
	)
	(footprint "antmicro-footprints:LED_0603_1608Metric_G"
		(layer "F.Cu")
		(at 59.3 123.4 90)
		(descr "LED SMD 0603 Green")
		(tags "LED SMD 0603 Green")
		(property "Reference" "D53"
			(at -1.2 1.5 90)
			(layer "F.SilkS")
			(effects
				(font
					(size 0.7 0.7)
					(thickness 0.15)
				)
				(justify left bottom)
			)
		)
		(property "Value" "LED_G_0603_LTST-C190GKT"
			(at -0.001 1.599 90)
			(layer "F.Fab")
			(effects
				(font
					(size 0.7 0.7)
					(thickness 0.15)
				)
				(justify left bottom)
			)
		)
		(property "Footprint" "antmicro-footprints:LED_0603_1608Metric_G"
			(at 0 0 90)
			(layer "F.Fab")
			(hide yes)
			(effects
				(font
					(size 1.27 1.27)
					(thickness 0.15)
				)
			)
		)
		(property "Datasheet" "https://media.digikey.com/pdf/Data%20Sheets/Lite-On%20PDFs/LTST-C190GKT.pdf"
			(at 0 0 90)
			(layer "F.Fab")
			(hide yes)
			(effects
				(font
					(size 1.27 1.27)
					(thickness 0.15)
				)
			)
		)
		(property "Author" "Antmicro"
			(at 182.7 64.1 0)
			(layer "F.Fab")
			(hide yes)
			(effects
				(font
					(size 1 1)
					(thickness 0.15)
				)
			)
		)
		(property "Color" "Green"
			(at 182.7 64.1 0)
			(layer "F.Fab")
			(hide yes)
			(effects
				(font
					(size 1 1)
					(thickness 0.15)
				)
			)
		)
		(property "License" "Apache-2.0"
			(at 182.7 64.1 0)
			(layer "F.Fab")
			(hide yes)
			(effects
				(font
					(size 1 1)
					(thickness 0.15)
				)
			)
		)
		(property "MPN" "LTST-C190GKT"
			(at 182.7 64.1 0)
			(layer "F.Fab")
			(hide yes)
			(effects
				(font
					(size 1 1)
					(thickness 0.15)
				)
			)
		)
		(property "Manufacturer" "Lite-On"
			(at 182.7 64.1 0)
			(layer "F.Fab")
			(hide yes)
			(effects
				(font
					(size 1 1)
					(thickness 0.15)
				)
			)
		)
		(sheetname "Supply")
		(sheetfile "supply.kicad_sch")
		(attr smd)
		(fp_line
			(start 0.22 -0.35)
			(end -0.22 -0.35)
			(stroke
				(width 0.15)
				(type solid)
			)
			(layer "F.SilkS")
		)
		(fp_line
			(start -1.18 -0.319)
			(end -1.18 0.321)
			(stroke
				(width 0.15)
				(type solid)
			)
			(layer "F.SilkS")
		)
		(fp_line
			(start 0.105328 0.001008)
			(end 0.24 0.001)
			(stroke
				(width 0.1)
				(type solid)
			)
			(layer "F.SilkS")
		)
		(fp_line
			(start -0.094672 0.001008)
			(end 0.105328 -0.198992)
			(stroke
				(width 0.1)
				(type solid)
			)
			(layer "F.SilkS")
		)
		(fp_line
			(start -0.094672 0.001008)
			(end -0.24 0.001008)
			(stroke
				(width 0.1)
				(type solid)
			)
			(layer "F.SilkS")
		)
		(fp_line
			(start 0.105328 0.201008)
			(end 0.105328 -0.198992)
			(stroke
				(width 0.1)
				(type solid)
			)
			(layer "F.SilkS")
		)
		(fp_line
			(start 0.105328 0.201008)
			(end -0.094672 0.001008)
			(stroke
				(width 0.1)
				(type solid)
			)
			(layer "F.SilkS")
		)
		(fp_line
			(start -0.094672 0.201008)
			(end -0.094672 -0.198992)
			(stroke
				(width 0.1)
				(type solid)
			)
			(layer "F.SilkS")
		)
		(fp_line
			(start 0.22 0.35)
			(end -0.22 0.35)
			(stroke
				(width 0.15)
				(type solid)
			)
			(layer "F.SilkS")
		)
		(fp_rect
			(start 1.25 0.65)
			(end -1.25 -0.65)
			(stroke
				(width 0.05)
				(type solid)
			)
			(fill none)
			(layer "F.CrtYd")
		)
		(fp_line
			(start 0.201 -0.202)
			(end -0.101 0)
			(stroke
				(width 0.15)
				(type solid)
			)
			(layer "F.Fab")
		)
		(fp_line
			(start -0.199 -0.202)
			(end -0.199 0.1)
			(stroke
				(width 0.15)
				(type solid)
			)
			(layer "F.Fab")
		)
		(fp_line
			(start 0.599 0)
			(end 0.201 0)
			(stroke
				(width 0.15)
				(type solid)
			)
			(layer "F.Fab")
		)
		(fp_line
			(start 0.201 0)
			(end 0.201 -0.202)
			(stroke
				(width 0.15)
				(type solid)
			)
			(layer "F.Fab")
		)
		(fp_line
			(start -0.101 0)
			(end 0.201 0.2)
			(stroke
				(width 0.15)
				(type solid)
			)
			(layer "F.Fab")
		)
		(fp_line
			(start -0.199 0)
			(end -0.597 0)
			(stroke
				(width 0.15)
				(type solid)
			)
			(layer "F.Fab")
		)
		(fp_line
			(start 0.201 0.2)
			(end 0.201 0)
			(stroke
				(width 0.15)
				(type solid)
			)
			(layer "F.Fab")
		)
		(fp_line
			(start -0.199 0.2)
			(end -0.199 0.1)
			(stroke
				(width 0.15)
				(type solid)
			)
			(layer "F.Fab")
		)
		(fp_rect
			(start 0.848 0.4)
			(end -0.85 -0.402)
			(stroke
				(width 0.15)
				(type solid)
			)
			(fill none)
			(layer "F.Fab")
		)
		(fp_text user "Author: Antmicro"
			(at -1.4224 4.799 90)
			(layer "F.Fab")
			(hide yes)
			(effects
				(font
					(size 0.7 0.7)
					(thickness 0.15)
				)
				(justify left bottom)
			)
		)
		(fp_text user "License: Apache-2.0"
			(at -1.4224 3.599 90)
			(layer "F.Fab")
			(hide yes)
			(effects
				(font
					(size 0.7 0.7)
					(thickness 0.15)
				)
				(justify left bottom)
			)
		)
		(fp_text user "${REFERENCE}"
			(at -1.4224 5.999 90)
			(layer "F.Fab")
			(hide yes)
			(effects
				(font
					(size 0.7 0.7)
					(thickness 0.15)
				)
				(justify left bottom)
			)
		)
		(pad "1" smd roundrect
			(at -0.7 0 270)
			(size 0.8 1)
			(layers "F.Cu" "F.Paste" "F.Mask")
			(roundrect_rratio 0.2)
			(net 1 "GND")
			(pinfunction "C")
			(pintype "passive")
		)
		(pad "2" smd roundrect
			(at 0.7 0 270)
			(size 0.8 1)
			(layers "F.Cu" "F.Paste" "F.Mask")
			(roundrect_rratio 0.2)
			(net 654 "Net-(D53-A)")
			(pinfunction "A")
			(pintype "passive")
		)
	)
	(footprint "antmicro-footprints:C_0603_1608Metric"
		(layer "F.Cu")
		(at 105.05 102.3 90)
		(descr "Capacitor SMD 0603")
		(tags "capacitor 0603")
		(property "Reference" "C66"
			(at 1.1 0.45 90)
			(layer "F.SilkS")
			(effects
				(font
					(size 0.7 0.7)
					(thickness 0.15)
				)
				(justify left bottom)
			)
		)
		(property "Value" "C_10u_0603"
			(at 0 1.6 90)
			(layer "F.Fab")
			(effects
				(font
					(size 0.7 0.7)
					(thickness 0.15)
				)
				(justify left bottom)
			)
		)
		(property "Footprint" "antmicro-footprints:C_0603_1608Metric"
			(at 0 0 90)
			(layer "F.Fab")
			(hide yes)
			(effects
				(font
					(size 1.27 1.27)
					(thickness 0.15)
				)
			)
		)
		(property "Datasheet" "https://www.murata.com/products/productdetail?partno=GRM188R61A106KE69%23"
			(at 0 0 90)
			(layer "F.Fab")
			(hide yes)
			(effects
				(font
					(size 1.27 1.27)
					(thickness 0.15)
				)
			)
		)
		(property "Author" "Antmicro"
			(at 207.35 -2.75 0)
			(layer "F.Fab")
			(hide yes)
			(effects
				(font
					(size 1 1)
					(thickness 0.15)
				)
			)
		)
		(property "Dielectric" "template_dielectric"
			(at 207.35 -2.75 0)
			(layer "F.Fab")
			(hide yes)
			(effects
				(font
					(size 1 1)
					(thickness 0.15)
				)
			)
		)
		(property "License" "Apache-2.0"
			(at 207.35 -2.75 0)
			(layer "F.Fab")
			(hide yes)
			(effects
				(font
					(size 1 1)
					(thickness 0.15)
				)
			)
		)
		(property "MPN" "GRM188R61A106KE69D"
			(at 207.35 -2.75 0)
			(layer "F.Fab")
			(hide yes)
			(effects
				(font
					(size 1 1)
					(thickness 0.15)
				)
			)
		)
		(property "Manufacturer" "Murata"
			(at 207.35 -2.75 0)
			(layer "F.Fab")
			(hide yes)
			(effects
				(font
					(size 1 1)
					(thickness 0.15)
				)
			)
		)
		(property "Val" "10u"
			(at 207.35 -2.75 0)
			(layer "F.Fab")
			(hide yes)
			(effects
				(font
					(size 1 1)
					(thickness 0.15)
				)
			)
		)
		(property "Voltage" ""
			(at 207.35 -2.75 0)
			(layer "F.Fab")
			(hide yes)
			(effects
				(font
					(size 1 1)
					(thickness 0.15)
				)
			)
		)
		(sheetname "USB3")
		(sheetfile "usb3.kicad_sch")
		(attr smd)
		(fp_line
			(start -0.15 -0.4)
			(end 0.15 -0.4)
			(stroke
				(width 0.15)
				(type solid)
			)
			(layer "F.SilkS")
		)
		(fp_line
			(start -0.15 0.4)
			(end 0.15 0.4)
			(stroke
				(width 0.15)
				(type solid)
			)
			(layer "F.SilkS")
		)
		(fp_rect
			(start -1.25 -0.65)
			(end 1.25 0.65)
			(stroke
				(width 0.05)
				(type solid)
			)
			(fill none)
			(layer "F.CrtYd")
		)
		(fp_rect
			(start -0.8 -0.4)
			(end 0.8 0.4)
			(stroke
				(width 0.15)
				(type solid)
			)
			(fill none)
			(layer "F.Fab")
		)
		(fp_text user "Author: Antmicro"
			(at -1.682 4.894 90)
			(layer "F.Fab")
			(hide yes)
			(effects
				(font
					(size 0.7 0.7)
					(thickness 0.15)
				)
				(justify left bottom)
			)
		)
		(fp_text user "License: Apache-2.0"
			(at -1.682 5.895 90)
			(layer "F.Fab")
			(hide yes)
			(effects
				(font
					(size 0.7 0.7)
					(thickness 0.15)
				)
				(justify left bottom)
			)
		)
		(fp_text user "${REFERENCE}"
			(at -1.682 3.895 90)
			(layer "F.Fab")
			(hide yes)
			(effects
				(font
					(size 0.7 0.7)
					(thickness 0.15)
				)
				(justify left bottom)
			)
		)
		(pad "1" smd roundrect
			(at -0.7 0 90)
			(size 0.8 1)
			(layers "F.Cu" "F.Paste" "F.Mask")
			(roundrect_rratio 0.2)
			(net 99 "+5V")
			(pintype "passive")
		)
		(pad "2" smd roundrect
			(at 0.7 0 90)
			(size 0.8 1)
			(layers "F.Cu" "F.Paste" "F.Mask")
			(roundrect_rratio 0.2)
			(net 1 "GND")
			(pintype "passive")
		)
	)
)
